(kicad_pcb
	(version 20260206)
	(generator "pcbnew")
	(generator_version "10.0")
	(general
		(thickness 1.6)
		(legacy_teardrops no)
	)
	(paper "A4")
	(title_block
		(title "pdpb — Lightning_PDPB_BRD.brd")
		(comment 1 "Lightning (Wiwynn / Facebook NVMe JBOF) / footprints 204-210 of 1140")
	)
	(layers
		(0 "F.Cu" signal "TOP")
		(4 "In1.Cu" signal "L2GND")
		(6 "In2.Cu" signal "L3")
		(8 "In3.Cu" signal "L4VCC")
		(10 "In4.Cu" signal "L5VCC")
		(12 "In5.Cu" signal "L6")
		(14 "In6.Cu" signal "L7GND")
		(2 "B.Cu" signal "BOTTOM")
		(9 "F.Adhes" user "F.Adhesive")
		(11 "B.Adhes" user "B.Adhesive")
		(13 "F.Paste" user "Package Geometry/Pastemask Top")
		(15 "B.Paste" user "Package Geometry/Pastemask Bottom")
		(5 "F.SilkS" user "Ref Des/Silkscreen Top")
		(7 "B.SilkS" user "Ref Des/Silkscreen Bottom")
		(1 "F.Mask" user "Board Geometry/Soldermask Top")
		(3 "B.Mask" user "Board Geometry/Soldermask Bottom")
		(17 "Dwgs.User" user "User.Drawings")
		(19 "Cmts.User" user "User.Comments")
		(21 "Eco1.User" user "User.Eco1")
		(23 "Eco2.User" user "User.Eco2")
		(25 "Edge.Cuts" user "Board Geometry/Outline")
		(27 "Margin" user)
		(31 "F.CrtYd" user "Package Geometry/Place Bound Top")
		(29 "B.CrtYd" user "Package Geometry/Place Bound Bottom")
		(35 "F.Fab" user "Ref Des/Assembly Top")
		(33 "B.Fab" user "Ref Des/Assembly Bottom")
	)
	(footprint ""
		(layer "F.Cu")
		(at 90.297 -440.436 180)
		(property "Reference" "R9066"
			(at 0 0 180)
			(layer "F.SilkS")
			(hide yes)
			(effects
				(font
					(size 1.27 1.27)
				)
			)
		)
		(property "Value" "27R2F-GP"
			(at 0.064008 -3.993896 180)
			(unlocked yes)
			(layer "F.Fab")
			(hide yes)
			(effects
				(font
					(size 1.016 1.016)
					(thickness 0.1524)
				)
			)
		)
		(property "Device Type" "R402H16"
			(at 0.064008 -5.517896 180)
			(unlocked yes)
			(layer "F.Fab")
			(hide yes)
			(effects
				(font
					(size 1.016 1.016)
					(thickness 0.1524)
				)
			)
		)
		(duplicate_pad_numbers_are_jumpers no)
		(fp_line
			(start 0.508 -0.9398)
			(end -0.508 -0.9398)
			(stroke
				(width 0.1524)
				(type default)
			)
			(layer "F.SilkS")
		)
		(fp_line
			(start -0.508 -0.9398)
			(end -0.508 0.9398)
			(stroke
				(width 0.1524)
				(type default)
			)
			(layer "F.SilkS")
		)
		(fp_rect
			(start -0.508 0.9398)
			(end 0.508 -0.9398)
			(stroke
				(width 0)
				(type default)
			)
			(fill no)
			(layer "F.CrtYd")
		)
		(fp_rect
			(start -0.508 0.9398)
			(end 0.508 -0.9398)
			(stroke
				(width 0)
				(type default)
			)
			(fill no)
			(layer "F.Fab")
		)
		(pad "1" smd custom
			(at 0 -0.4445 180)
			(size 0.1397 0.1397)
			(layers "F.Cu" "F.Mask" "F.Paste")
			(net "PE_CLK_100M_DR5_2_R_N")
			(options
				(clearance outline)
				(anchor circle)
			)
			(primitives
				(gr_poly
					(pts
						(arc
							(start -0.1778 -0.2794)
							(mid -0.249642 -0.249642)
							(end -0.2794 -0.1778)
						)
						(arc
							(start -0.2794 0.1778)
							(mid -0.249642 0.249642)
							(end -0.1778 0.2794)
						)
						(arc
							(start 0.1778 0.2794)
							(mid 0.249642 0.249642)
							(end 0.2794 0.1778)
						)
						(arc
							(start 0.2794 -0.1778)
							(mid 0.249642 -0.249642)
							(end 0.1778 -0.2794)
						)
					)
					(width 0)
					(fill yes)
				)
			)
		)
		(pad "2" smd custom
			(at 0 0.4445 180)
			(size 0.1397 0.1397)
			(layers "F.Cu" "F.Mask" "F.Paste")
			(net "PE_CLK100M_DR5_2_N")
			(options
				(clearance outline)
				(anchor circle)
			)
			(primitives
				(gr_poly
					(pts
						(arc
							(start -0.1778 -0.2794)
							(mid -0.249642 -0.249642)
							(end -0.2794 -0.1778)
						)
						(arc
							(start -0.2794 0.1778)
							(mid -0.249642 0.249642)
							(end -0.1778 0.2794)
						)
						(arc
							(start 0.1778 0.2794)
							(mid 0.249642 0.249642)
							(end 0.2794 0.1778)
						)
						(arc
							(start 0.2794 -0.1778)
							(mid 0.249642 -0.249642)
							(end 0.1778 -0.2794)
						)
					)
					(width 0)
					(fill yes)
				)
			)
		)
	)
	(footprint ""
		(layer "F.Cu")
		(at 246.126 -416.941)
		(property "Reference" "TP3"
			(at 0 0 0)
			(layer "F.SilkS")
			(hide yes)
			(effects
				(font
					(size 1.27 1.27)
				)
			)
		)
		(property "Value" "TPAD28-2-GP"
			(at -0.0127 -1.6637 0)
			(unlocked yes)
			(layer "F.Fab")
			(hide yes)
			(effects
				(font
					(size 1.016 1.016)
					(thickness 0.1524)
				)
			)
		)
		(property "Device Type" "TPAD28"
			(at -0.0127 -3.1877 0)
			(unlocked yes)
			(layer "F.Fab")
			(hide yes)
			(effects
				(font
					(size 1.016 1.016)
					(thickness 0.1524)
				)
			)
		)
		(duplicate_pad_numbers_are_jumpers no)
		(fp_poly
			(pts
				(arc
					(start 0.3556 0)
					(mid -0.3556 0)
					(end 0.3556 0)
				)
			)
			(stroke
				(width 0)
				(type default)
			)
			(fill no)
			(layer "F.CrtYd")
		)
		(fp_poly
			(pts
				(arc
					(start 0.6096 0)
					(mid -0.6096 0)
					(end 0.6096 0)
				)
			)
			(stroke
				(width 0)
				(type default)
			)
			(fill no)
			(layer "F.Fab")
		)
		(pad "1" smd circle
			(at 0 0)
			(size 0.7112 0.7112)
			(layers "F.Cu" "F.Mask" "F.Paste")
			(net "N70914768")
		)
	)
	(footprint ""
		(layer "F.Cu")
		(at 107.442 -434.467 -90)
		(property "Reference" "R9590"
			(at 0 0 270)
			(layer "F.SilkS")
			(hide yes)
			(effects
				(font
					(size 1.27 1.27)
				)
			)
		)
		(property "Value" "10R2F-L-GP"
			(at 0.064008 -3.993896 270)
			(unlocked yes)
			(layer "F.Fab")
			(hide yes)
			(effects
				(font
					(size 1.016 1.016)
					(thickness 0.1524)
				)
			)
		)
		(property "Device Type" "R402H14"
			(at 0.064008 -5.517896 270)
			(unlocked yes)
			(layer "F.Fab")
			(hide yes)
			(effects
				(font
					(size 1.016 1.016)
					(thickness 0.1524)
				)
			)
		)
		(duplicate_pad_numbers_are_jumpers no)
		(fp_line
			(start -0.508 -0.9398)
			(end -0.508 0.9398)
			(stroke
				(width 0.1524)
				(type default)
			)
			(layer "F.SilkS")
		)
		(fp_line
			(start 0.508 -0.9398)
			(end -0.508 -0.9398)
			(stroke
				(width 0.1524)
				(type default)
			)
			(layer "F.SilkS")
		)
		(fp_rect
			(start -0.508 0.9398)
			(end 0.508 -0.9398)
			(stroke
				(width 0)
				(type default)
			)
			(fill no)
			(layer "F.CrtYd")
		)
		(fp_rect
			(start -0.508 0.9398)
			(end 0.508 -0.9398)
			(stroke
				(width 0)
				(type default)
			)
			(fill no)
			(layer "F.Fab")
		)
		(pad "1" smd custom
			(at 0 -0.4445 270)
			(size 0.1397 0.1397)
			(layers "F.Cu" "F.Mask" "F.Paste")
			(net "SSD_PRSNT_NET0")
			(options
				(clearance outline)
				(anchor circle)
			)
			(primitives
				(gr_poly
					(pts
						(arc
							(start -0.1778 -0.2794)
							(mid -0.249642 -0.249642)
							(end -0.2794 -0.1778)
						)
						(arc
							(start -0.2794 0.1778)
							(mid -0.249642 0.249642)
							(end -0.1778 0.2794)
						)
						(arc
							(start 0.1778 0.2794)
							(mid 0.249642 0.249642)
							(end 0.2794 0.1778)
						)
						(arc
							(start 0.2794 -0.1778)
							(mid 0.249642 -0.249642)
							(end 0.1778 -0.2794)
						)
					)
					(width 0)
					(fill yes)
				)
			)
		)
		(pad "2" smd custom
			(at 0 0.4445 270)
			(size 0.1397 0.1397)
			(layers "F.Cu" "F.Mask" "F.Paste")
			(net "SSD_PRSNT0")
			(options
				(clearance outline)
				(anchor circle)
			)
			(primitives
				(gr_poly
					(pts
						(arc
							(start -0.1778 -0.2794)
							(mid -0.249642 -0.249642)
							(end -0.2794 -0.1778)
						)
						(arc
							(start -0.2794 0.1778)
							(mid -0.249642 0.249642)
							(end -0.1778 0.2794)
						)
						(arc
							(start 0.1778 0.2794)
							(mid 0.249642 0.249642)
							(end 0.2794 0.1778)
						)
						(arc
							(start 0.2794 -0.1778)
							(mid 0.249642 -0.249642)
							(end 0.1778 -0.2794)
						)
					)
					(width 0)
					(fill yes)
				)
			)
		)
	)
	(footprint ""
		(layer "F.Cu")
		(at 35.0012 -86.3346)
		(property "Reference" "PC1196"
			(at 0 0 0)
			(layer "F.SilkS")
			(hide yes)
			(effects
				(font
					(size 1.27 1.27)
				)
			)
		)
		(property "Value" "SC22U25V6KX-GP-U"
			(at -2.860802 -5.279644 0)
			(unlocked yes)
			(layer "F.Fab")
			(hide yes)
			(effects
				(font
					(size 1.016 1.016)
					(thickness 0.1524)
				)
			)
		)
		(property "Device Type" "C1206-TO0D3H75"
			(at -2.860802 -6.803644 0)
			(unlocked yes)
			(layer "F.Fab")
			(hide yes)
			(effects
				(font
					(size 1.016 1.016)
					(thickness 0.1524)
				)
			)
		)
		(duplicate_pad_numbers_are_jumpers no)
		(fp_line
			(start -1.3081 -2.3749)
			(end 1.3081 -2.3749)
			(stroke
				(width 0.1524)
				(type default)
			)
			(layer "F.SilkS")
		)
		(fp_line
			(start -1.3081 2.3749)
			(end -1.3081 -2.3749)
			(stroke
				(width 0.1524)
				(type default)
			)
			(layer "F.SilkS")
		)
		(fp_line
			(start 1.3081 -2.3749)
			(end 1.3081 2.3749)
			(stroke
				(width 0.1524)
				(type default)
			)
			(layer "F.SilkS")
		)
		(fp_line
			(start 1.3081 2.3749)
			(end -1.3081 2.3749)
			(stroke
				(width 0.1524)
				(type default)
			)
			(layer "F.SilkS")
		)
		(fp_rect
			(start -0.8001 1.6002)
			(end 0.8001 -1.6002)
			(stroke
				(width 0)
				(type default)
			)
			(fill no)
			(layer "F.CrtYd")
		)
		(fp_poly
			(pts
				(xy -1.5621 2.4511) (xy -1.5621 1.6002) (xy 0.8001 1.6002) (xy 0.8001 -1.6002) (xy -0.8001 -1.6002)
				(xy -0.8001 1.5875) (xy -1.5621 1.5875) (xy -1.5621 -2.4511) (xy 1.5621 -2.4511) (xy 1.5621 2.4511)
			)
			(stroke
				(width 0)
				(type default)
			)
			(fill no)
			(layer "F.CrtYd")
		)
		(fp_rect
			(start -1.5621 2.4511)
			(end 1.5621 -2.4511)
			(stroke
				(width 0)
				(type default)
			)
			(fill no)
			(layer "F.Fab")
		)
		(pad "1" smd rect
			(at 0 -1.392936)
			(size 2.1082 1.4478)
			(layers "F.Cu" "F.Mask" "F.Paste")
			(net "P12V_SSD9")
		)
		(pad "2" smd rect
			(at 0 1.392936)
			(size 2.1082 1.4478)
			(layers "F.Cu" "F.Mask" "F.Paste")
			(net "GND")
		)
	)
	(footprint ""
		(layer "F.Cu")
		(at 107.442 -207.645 -90)
		(property "Reference" "R9595"
			(at 0 0 270)
			(layer "F.SilkS")
			(hide yes)
			(effects
				(font
					(size 1.27 1.27)
				)
			)
		)
		(property "Value" "10R2F-L-GP"
			(at 0.064008 -3.993896 270)
			(unlocked yes)
			(layer "F.Fab")
			(hide yes)
			(effects
				(font
					(size 1.016 1.016)
					(thickness 0.1524)
				)
			)
		)
		(property "Device Type" "R402H14"
			(at 0.064008 -5.517896 270)
			(unlocked yes)
			(layer "F.Fab")
			(hide yes)
			(effects
				(font
					(size 1.016 1.016)
					(thickness 0.1524)
				)
			)
		)
		(duplicate_pad_numbers_are_jumpers no)
		(fp_line
			(start -0.508 -0.9398)
			(end -0.508 0.9398)
			(stroke
				(width 0.1524)
				(type default)
			)
			(layer "F.SilkS")
		)
		(fp_line
			(start 0.508 -0.9398)
			(end -0.508 -0.9398)
			(stroke
				(width 0.1524)
				(type default)
			)
			(layer "F.SilkS")
		)
		(fp_rect
			(start -0.508 0.9398)
			(end 0.508 -0.9398)
			(stroke
				(width 0)
				(type default)
			)
			(fill no)
			(layer "F.CrtYd")
		)
		(fp_rect
			(start -0.508 0.9398)
			(end 0.508 -0.9398)
			(stroke
				(width 0)
				(type default)
			)
			(fill no)
			(layer "F.Fab")
		)
		(pad "1" smd custom
			(at 0 -0.4445 270)
			(size 0.1397 0.1397)
			(layers "F.Cu" "F.Mask" "F.Paste")
			(net "SSD3_CLK0_OE_N")
			(options
				(clearance outline)
				(anchor circle)
			)
			(primitives
				(gr_poly
					(pts
						(arc
							(start -0.1778 -0.2794)
							(mid -0.249642 -0.249642)
							(end -0.2794 -0.1778)
						)
						(arc
							(start -0.2794 0.1778)
							(mid -0.249642 0.249642)
							(end -0.1778 0.2794)
						)
						(arc
							(start 0.1778 0.2794)
							(mid 0.249642 0.249642)
							(end 0.2794 0.1778)
						)
						(arc
							(start 0.2794 -0.1778)
							(mid 0.249642 -0.249642)
							(end 0.1778 -0.2794)
						)
					)
					(width 0)
					(fill yes)
				)
			)
		)
		(pad "2" smd custom
			(at 0 0.4445 270)
			(size 0.1397 0.1397)
			(layers "F.Cu" "F.Mask" "F.Paste")
			(net "SSD3_CLK0_OE_R_N")
			(options
				(clearance outline)
				(anchor circle)
			)
			(primitives
				(gr_poly
					(pts
						(arc
							(start -0.1778 -0.2794)
							(mid -0.249642 -0.249642)
							(end -0.2794 -0.1778)
						)
						(arc
							(start -0.2794 0.1778)
							(mid -0.249642 0.249642)
							(end -0.1778 0.2794)
						)
						(arc
							(start 0.1778 0.2794)
							(mid 0.249642 0.249642)
							(end 0.2794 0.1778)
						)
						(arc
							(start 0.2794 -0.1778)
							(mid 0.249642 -0.249642)
							(end 0.1778 -0.2794)
						)
					)
					(width 0)
					(fill yes)
				)
			)
		)
	)
	(footprint ""
		(layer "F.Cu")
		(at 82.931 -212.979 90)
		(property "Reference" "SR952"
			(at 0 0 90)
			(layer "F.SilkS")
			(hide yes)
			(effects
				(font
					(size 1.27 1.27)
				)
			)
		)
		(property "Value" "4K7R2F-GP"
			(at 0.064008 -3.993896 90)
			(unlocked yes)
			(layer "F.Fab")
			(hide yes)
			(effects
				(font
					(size 1.016 1.016)
					(thickness 0.1524)
				)
			)
		)
		(property "Device Type" "R402H16"
			(at 0.064008 -5.517896 90)
			(unlocked yes)
			(layer "F.Fab")
			(hide yes)
			(effects
				(font
					(size 1.016 1.016)
					(thickness 0.1524)
				)
			)
		)
		(duplicate_pad_numbers_are_jumpers no)
		(fp_line
			(start 0.508 -0.9398)
			(end -0.508 -0.9398)
			(stroke
				(width 0.1524)
				(type default)
			)
			(layer "F.SilkS")
		)
		(fp_line
			(start -0.508 -0.9398)
			(end -0.508 0.9398)
			(stroke
				(width 0.1524)
				(type default)
			)
			(layer "F.SilkS")
		)
		(fp_rect
			(start -0.508 0.9398)
			(end 0.508 -0.9398)
			(stroke
				(width 0)
				(type default)
			)
			(fill no)
			(layer "F.CrtYd")
		)
		(fp_rect
			(start -0.508 0.9398)
			(end 0.508 -0.9398)
			(stroke
				(width 0)
				(type default)
			)
			(fill no)
			(layer "F.Fab")
		)
		(pad "1" smd custom
			(at 0 -0.4445 90)
			(size 0.1397 0.1397)
			(layers "F.Cu" "F.Mask" "F.Paste")
			(net "VDD_DIFF_3")
			(options
				(clearance outline)
				(anchor circle)
			)
			(primitives
				(gr_poly
					(pts
						(arc
							(start -0.1778 -0.2794)
							(mid -0.249642 -0.249642)
							(end -0.2794 -0.1778)
						)
						(arc
							(start -0.2794 0.1778)
							(mid -0.249642 0.249642)
							(end -0.1778 0.2794)
						)
						(arc
							(start 0.1778 0.2794)
							(mid 0.249642 0.249642)
							(end 0.2794 0.1778)
						)
						(arc
							(start 0.2794 -0.1778)
							(mid 0.249642 -0.249642)
							(end 0.1778 -0.2794)
						)
					)
					(width 0)
					(fill yes)
				)
			)
		)
		(pad "2" smd custom
			(at 0 0.4445 90)
			(size 0.1397 0.1397)
			(layers "F.Cu" "F.Mask" "F.Paste")
			(net "P3V3_PG")
			(options
				(clearance outline)
				(anchor circle)
			)
			(primitives
				(gr_poly
					(pts
						(arc
							(start -0.1778 -0.2794)
							(mid -0.249642 -0.249642)
							(end -0.2794 -0.1778)
						)
						(arc
							(start -0.2794 0.1778)
							(mid -0.249642 0.249642)
							(end -0.1778 0.2794)
						)
						(arc
							(start 0.1778 0.2794)
							(mid 0.249642 0.249642)
							(end 0.2794 0.1778)
						)
						(arc
							(start 0.2794 -0.1778)
							(mid 0.249642 -0.249642)
							(end 0.1778 -0.2794)
						)
					)
					(width 0)
					(fill yes)
				)
			)
		)
	)
	(footprint ""
		(layer "F.Cu")
		(at 84.455 -426.974 90)
		(property "Reference" "R419"
			(at 0 0 90)
			(layer "F.SilkS")
			(hide yes)
			(effects
				(font
					(size 1.27 1.27)
				)
			)
		)
		(property "Value" "0R2J-2-GP"
			(at 0.064008 -3.993896 90)
			(unlocked yes)
			(layer "F.Fab")
			(hide yes)
			(effects
				(font
					(size 1.016 1.016)
					(thickness 0.1524)
				)
			)
		)
		(property "Device Type" "R402H16"
			(at 0.064008 -5.517896 90)
			(unlocked yes)
			(layer "F.Fab")
			(hide yes)
			(effects
				(font
					(size 1.016 1.016)
					(thickness 0.1524)
				)
			)
		)
		(duplicate_pad_numbers_are_jumpers no)
		(fp_line
			(start 0.508 -0.9398)
			(end -0.508 -0.9398)
			(stroke
				(width 0.1524)
				(type default)
			)
			(layer "F.SilkS")
		)
		(fp_line
			(start -0.508 -0.9398)
			(end -0.508 0.9398)
			(stroke
				(width 0.1524)
				(type default)
			)
			(layer "F.SilkS")
		)
		(fp_rect
			(start -0.508 0.9398)
			(end 0.508 -0.9398)
			(stroke
				(width 0)
				(type default)
			)
			(fill no)
			(layer "F.CrtYd")
		)
		(fp_rect
			(start -0.508 0.9398)
			(end 0.508 -0.9398)
			(stroke
				(width 0)
				(type default)
			)
			(fill no)
			(layer "F.Fab")
		)
		(pad "1" smd custom
			(at 0 -0.4445 90)
			(size 0.1397 0.1397)
			(layers "F.Cu" "F.Mask" "F.Paste")
			(net "BMC_I2C_SCL_BUF_9")
			(options
				(clearance outline)
				(anchor circle)
			)
			(primitives
				(gr_poly
					(pts
						(arc
							(start -0.1778 -0.2794)
							(mid -0.249642 -0.249642)
							(end -0.2794 -0.1778)
						)
						(arc
							(start -0.2794 0.1778)
							(mid -0.249642 0.249642)
							(end -0.1778 0.2794)
						)
						(arc
							(start 0.1778 0.2794)
							(mid 0.249642 0.249642)
							(end 0.2794 0.1778)
						)
						(arc
							(start 0.2794 -0.1778)
							(mid 0.249642 -0.249642)
							(end 0.1778 -0.2794)
						)
					)
					(width 0)
					(fill yes)
				)
			)
		)
		(pad "2" smd custom
			(at 0 0.4445 90)
			(size 0.1397 0.1397)
			(layers "F.Cu" "F.Mask" "F.Paste")
			(net "I2C_SCL_BUF_9_EU1_R")
			(options
				(clearance outline)
				(anchor circle)
			)
			(primitives
				(gr_poly
					(pts
						(arc
							(start -0.1778 -0.2794)
							(mid -0.249642 -0.249642)
							(end -0.2794 -0.1778)
						)
						(arc
							(start -0.2794 0.1778)
							(mid -0.249642 0.249642)
							(end -0.1778 0.2794)
						)
						(arc
							(start 0.1778 0.2794)
							(mid 0.249642 0.249642)
							(end 0.2794 0.1778)
						)
						(arc
							(start 0.2794 -0.1778)
							(mid 0.249642 -0.249642)
							(end 0.1778 -0.2794)
						)
					)
					(width 0)
					(fill yes)
				)
			)
		)
	)
)
